(kicad_pcb
	(version 20221018)
	(generator pcbnew)
	(general
    (thickness 1.586)
  )
	(paper "A4")
	(title_block
    (date "2024-03-26")
    (rev "1.1.3")
		(comment 9 "footprints 87-92 of 146")
	)
	(layers
    (0 "F.Cu" signal)
    (1 "In1.Cu" power)
    (2 "In2.Cu" power)
    (31 "B.Cu" signal)
    (32 "B.Adhes" user "B.Adhesive")
    (33 "F.Adhes" user "F.Adhesive")
    (34 "B.Paste" user)
    (35 "F.Paste" user)
    (36 "B.SilkS" user "B.Silkscreen")
    (37 "F.SilkS" user "F.Silkscreen")
    (38 "B.Mask" user)
    (39 "F.Mask" user)
    (40 "Dwgs.User" user "User.Drawings")
    (41 "Cmts.User" user "User.Comments")
    (42 "Eco1.User" user "User.Eco1")
    (43 "Eco2.User" user "User.Eco2")
    (44 "Edge.Cuts" user)
    (45 "Margin" user)
    (46 "B.CrtYd" user "B.Courtyard")
    (47 "F.CrtYd" user "F.Courtyard")
    (48 "B.Fab" user)
    (49 "F.Fab" user)
  )
	(footprint "scalenode-cm4-baseboard-footprints:C_0805_2012Metric" (layer "B.Cu")
    (at 121.6 85.6)
    (descr "Capacitor SMD 0805")
    (tags "capacitor SMD 0805")
    (property "Author" "Antmicro")
    (property "Dielectric" "")
    (property "License" "Apache-2.0")
    (property "MPN" "0805ZD226MAT2A")
    (property "Manufacturer" "AVX")
    (property "Sheetfile" "supply.kicad_sch")
    (property "Sheetname" "Supply")
    (property "Val" "22u")
    (property "Voltage" "")
    (property "ki_description" " ")
    (attr smd)
    (fp_text reference "C18" (at -1.05 -1.15) (layer "B.SilkS")
        (effects (font (size 0.7 0.7) (thickness 0.15)) (justify right bottom mirror))
    )
    (fp_text value "C_22u_0805_10V" (at 0 -1.947) (layer "B.Fab")
        (effects (font (size 0.7 0.7) (thickness 0.15)) (justify right bottom mirror))
    )
    (fp_text user "Author: Antmicro" (at -1.9 -5.947) (layer "B.Fab") hide
        (effects (font (size 0.7 0.7) (thickness 0.15)) (justify right bottom mirror))
    )
    (fp_text user "License: Apache-2.0" (at -1.9 -4.947) (layer "B.Fab") hide
        (effects (font (size 0.7 0.7) (thickness 0.15)) (justify right bottom mirror))
    )
    (fp_text user "${REFERENCE}" (at -1.9 -3.947) (layer "B.Fab") hide
        (effects (font (size 0.7 0.7) (thickness 0.15)) (justify right bottom mirror))
    )
    (fp_line (start -0.3 -0.8) (end 0.3 -0.8)
      (stroke (width 0.15) (type solid)) (layer "B.SilkS"))
    (fp_line (start -0.3 0.8) (end 0.3 0.8)
      (stroke (width 0.15) (type solid)) (layer "B.SilkS"))
    (fp_rect (start -1.9 0.93) (end 1.9 -0.93)
      (stroke (width 0.05) (type solid)) (fill none) (layer "B.CrtYd"))
    (fp_rect (start -0.95 0.675) (end 0.95 -0.675)
      (stroke (width 0.15) (type solid)) (fill none) (layer "B.Fab"))
    (pad "1" smd rect (at -1.05 0) (size 1.2 1.2) (layers "B.Cu" "B.Paste" "B.Mask")
      (net 11 "GND") (pintype "passive"))
    (pad "2" smd rect (at 1.05 0) (size 1.2 1.2) (layers "B.Cu" "B.Paste" "B.Mask")
      (net 170 "3V3_SSD") (pintype "passive"))
  )
	(footprint "scalenode-cm4-baseboard-footprints:R_0402_1005Metric" (layer "B.Cu")
    (at 129.2 83.8 180)
    (descr "Resistor SMD 0402")
    (tags "resistor SMD 0402")
    (property "Author" "Antmicro")
    (property "License" "Apache-2.0")
    (property "MPN" "CR0402-FX-3322GLF")
    (property "Manufacturer" "Bourns")
    (property "Sheetfile" "supply.kicad_sch")
    (property "Sheetname" "Supply")
    (property "Tolerance" "1%")
    (property "Val" "33k2")
    (property "ki_description" "33k2 resistor in 0402 package with 1% tolerance")
    (attr smd)
    (fp_text reference "R18" (at -1.05 0.7) (layer "B.SilkS")
        (effects (font (size 0.7 0.7) (thickness 0.15)) (justify left bottom mirror))
    )
    (fp_text value "R_33k2_0402" (at 0 -1.4) (layer "B.Fab")
        (effects (font (size 0.7 0.7) (thickness 0.15)) (justify left bottom mirror))
    )
    (fp_text user "License: Apache-2.0" (at -0.95 -5.169) (layer "B.Fab") hide
        (effects (font (size 0.7 0.7) (thickness 0.15)) (justify left bottom mirror))
    )
    (fp_text user "${REFERENCE}" (at -0.95 -3.168) (layer "B.Fab") hide
        (effects (font (size 0.7 0.7) (thickness 0.15)) (justify left bottom mirror))
    )
    (fp_text user "Author: Antmicro" (at -0.95 -4.169) (layer "B.Fab") hide
        (effects (font (size 0.7 0.7) (thickness 0.15)) (justify left bottom mirror))
    )
    (fp_rect (start -0.95 0.48) (end 0.95 -0.48)
      (stroke (width 0.05) (type solid)) (fill none) (layer "B.CrtYd"))
    (fp_rect (start -0.5 0.25) (end 0.5 -0.25)
      (stroke (width 0.15) (type solid)) (fill none) (layer "B.Fab"))
    (pad "1" smd roundrect (at -0.485 0 180) (size 0.59 0.64) (layers "B.Cu" "B.Paste" "B.Mask") (roundrect_rratio 0.25)
      (net 252 "Net-(U2-FB)") (pintype "passive"))
    (pad "2" smd roundrect (at 0.485 0 180) (size 0.59 0.64) (layers "B.Cu" "B.Paste" "B.Mask") (roundrect_rratio 0.25)
      (net 170 "3V3_SSD") (pintype "passive"))
  )
	(footprint "scalenode-cm4-baseboard-footprints:USON-14_3.5x1.35_P0.5mm" (layer "B.Cu")
    (at 92.33 83.44)
    (descr "JEDEC MO-229")
    (property "Author" "Antmicro")
    (property "License" "Apache-2.0")
    (property "MPN" "SP3011-06UTG")
    (property "Manufacturer" "Littelfuse")
    (property "Sheetfile" "interfaces.kicad_sch")
    (property "Sheetname" "Interfaces")
    (attr smd)
    (fp_text reference "D2" (at 0.67 -2.19 180) (layer "B.SilkS")
        (effects (font (size 0.7 0.7) (thickness 0.15)) (justify left bottom mirror))
    )
    (fp_text value "SP3011-06UTG" (at -1.3 -3 180) (layer "B.Fab")
        (effects (font (size 0.7 0.7) (thickness 0.15)) (justify left bottom mirror))
    )
    (fp_text user "." (at -0.83 1.81 180) (layer "B.SilkS")
        (effects (font (size 1 1) (thickness 0.15)) (justify mirror))
    )
    (fp_text user "Author: Antmicro" (at -1.3 -5.4 180) (layer "B.Fab") hide
        (effects (font (size 0.7 0.7) (thickness 0.15)) (justify left bottom mirror))
    )
    (fp_text user "${REFERENCE}" (at -1.3 -4.2 180) (layer "B.Fab") hide
        (effects (font (size 0.7 0.7) (thickness 0.15)) (justify left bottom mirror))
    )
    (fp_text user "License: Apache-2.0" (at -1.3 -6.6 180) (layer "B.Fab") hide
        (effects (font (size 0.7 0.7) (thickness 0.15)) (justify left bottom mirror))
    )
    (fp_line (start -0.8 -1.75) (end 0.8 -1.75)
      (stroke (width 0.12) (type solid)) (layer "B.SilkS"))
    (fp_line (start -0.4 1.75) (end 0.8 1.75)
      (stroke (width 0.12) (type solid)) (layer "B.SilkS"))
    (fp_rect (start 1 1.9) (end -0.95 -1.9)
      (stroke (width 0.05) (type solid)) (fill none) (layer "B.CrtYd"))
    (fp_line (start -0.7 -1.75) (end -0.7 1.55)
      (stroke (width 0.1) (type solid)) (layer "B.Fab"))
    (fp_line (start -0.7 1.55) (end -0.5 1.75)
      (stroke (width 0.1) (type solid)) (layer "B.Fab"))
    (fp_line (start -0.5 1.75) (end 0.65 1.75)
      (stroke (width 0.1) (type solid)) (layer "B.Fab"))
    (fp_line (start 0.65 -1.75) (end -0.7 -1.75)
      (stroke (width 0.1) (type solid)) (layer "B.Fab"))
    (fp_line (start 0.65 1.75) (end 0.65 -1.75)
      (stroke (width 0.1) (type solid)) (layer "B.Fab"))
    (pad "1" smd roundrect (at -0.623 1.5 90) (size 0.2 0.5) (layers "B.Cu" "B.Paste" "B.Mask") (roundrect_rratio 0.25)
      (chamfer_ratio 0.2) (chamfer top_left)
      (net 28 "SD_DAT1") (pintype "passive"))
    (pad "2" smd roundrect (at -0.623 1 90) (size 0.2 0.5) (layers "B.Cu" "B.Paste" "B.Mask") (roundrect_rratio 0.25)
      (net 29 "SD_DAT0") (pintype "passive"))
    (pad "3" smd roundrect (at -0.623 0.5 90) (size 0.2 0.5) (layers "B.Cu" "B.Paste" "B.Mask") (roundrect_rratio 0.25)
      (net 30 "SD_CLK") (pintype "passive"))
    (pad "4" smd roundrect (at -0.623 0 90) (size 0.2 0.5) (layers "B.Cu" "B.Paste" "B.Mask") (roundrect_rratio 0.25)
      (net 31 "SD_CMD") (pintype "passive"))
    (pad "5" smd roundrect (at -0.623 -0.498 90) (size 0.2 0.5) (layers "B.Cu" "B.Paste" "B.Mask") (roundrect_rratio 0.25)
      (net 11 "GND") (pintype "passive"))
    (pad "6" smd roundrect (at -0.623 -0.998 90) (size 0.2 0.5) (layers "B.Cu" "B.Paste" "B.Mask") (roundrect_rratio 0.25)
      (net 32 "SD_DAT3") (pintype "passive"))
    (pad "7" smd roundrect (at -0.623 -1.499 90) (size 0.2 0.5) (layers "B.Cu" "B.Paste" "B.Mask") (roundrect_rratio 0.25)
      (net 33 "SD_DAT2") (pintype "passive"))
    (pad "8" smd roundrect (at 0.625 -1.499 90) (size 0.2 0.5) (layers "B.Cu" "B.Paste" "B.Mask") (roundrect_rratio 0.25)
      (net 33 "SD_DAT2") (pintype "passive"))
    (pad "9" smd roundrect (at 0.625 -0.998 90) (size 0.2 0.5) (layers "B.Cu" "B.Paste" "B.Mask") (roundrect_rratio 0.25)
      (net 32 "SD_DAT3") (pintype "passive"))
    (pad "10" smd roundrect (at 0.625 -0.498 90) (size 0.2 0.5) (layers "B.Cu" "B.Paste" "B.Mask") (roundrect_rratio 0.25)
      (net 11 "GND") (pintype "passive"))
    (pad "11" smd roundrect (at 0.625 0 90) (size 0.2 0.5) (layers "B.Cu" "B.Paste" "B.Mask") (roundrect_rratio 0.25)
      (net 31 "SD_CMD") (pintype "passive"))
    (pad "12" smd roundrect (at 0.625 0.5 90) (size 0.2 0.5) (layers "B.Cu" "B.Paste" "B.Mask") (roundrect_rratio 0.25)
      (net 30 "SD_CLK") (pintype "passive"))
    (pad "13" smd roundrect (at 0.625 1 90) (size 0.2 0.5) (layers "B.Cu" "B.Paste" "B.Mask") (roundrect_rratio 0.25)
      (net 29 "SD_DAT0") (pintype "passive"))
    (pad "14" smd roundrect (at 0.625 1.5 90) (size 0.2 0.5) (layers "B.Cu" "B.Paste" "B.Mask") (roundrect_rratio 0.25)
      (net 28 "SD_DAT1") (pintype "passive"))
  )
	(footprint "scalenode-cm4-baseboard-footprints:C_0805_2012Metric" (layer "B.Cu")
    (at 132.2 90.2 180)
    (descr "Capacitor SMD 0805")
    (tags "capacitor SMD 0805")
    (property "Author" "Antmicro")
    (property "Dielectric" "")
    (property "License" "Apache-2.0")
    (property "MPN" "0805ZD226MAT2A")
    (property "Manufacturer" "AVX")
    (property "Sheetfile" "supply.kicad_sch")
    (property "Sheetname" "Supply")
    (property "Val" "22u")
    (property "Voltage" "")
    (property "ki_description" " ")
    (attr smd)
    (fp_text reference "C16" (at -1.02 -1.84 180) (layer "B.SilkS")
        (effects (font (size 0.7 0.7) (thickness 0.15)) (justify left bottom mirror))
    )
    (fp_text value "C_22u_0805_10V" (at 0 -1.947) (layer "B.Fab")
        (effects (font (size 0.7 0.7) (thickness 0.15)) (justify left bottom mirror))
    )
    (fp_text user "License: Apache-2.0" (at -1.9 -4.947) (layer "B.Fab") hide
        (effects (font (size 0.7 0.7) (thickness 0.15)) (justify left bottom mirror))
    )
    (fp_text user "Author: Antmicro" (at -1.9 -5.947) (layer "B.Fab") hide
        (effects (font (size 0.7 0.7) (thickness 0.15)) (justify left bottom mirror))
    )
    (fp_text user "${REFERENCE}" (at -1.9 -3.947) (layer "B.Fab") hide
        (effects (font (size 0.7 0.7) (thickness 0.15)) (justify left bottom mirror))
    )
    (fp_line (start -0.3 -0.8) (end 0.3 -0.8)
      (stroke (width 0.15) (type solid)) (layer "B.SilkS"))
    (fp_line (start -0.3 0.8) (end 0.3 0.8)
      (stroke (width 0.15) (type solid)) (layer "B.SilkS"))
    (fp_rect (start -1.9 0.93) (end 1.9 -0.93)
      (stroke (width 0.05) (type solid)) (fill none) (layer "B.CrtYd"))
    (fp_rect (start -0.95 0.675) (end 0.95 -0.675)
      (stroke (width 0.15) (type solid)) (fill none) (layer "B.Fab"))
    (pad "1" smd rect (at -1.05 0 180) (size 1.2 1.2) (layers "B.Cu" "B.Paste" "B.Mask")
      (net 11 "GND") (pintype "passive"))
    (pad "2" smd rect (at 1.05 0 180) (size 1.2 1.2) (layers "B.Cu" "B.Paste" "B.Mask")
      (net 12 "VCC5V0") (pintype "passive"))
  )
	(footprint "scalenode-cm4-baseboard-footprints:L_Bourns-SRP3212A" (layer "B.Cu")
    (at 127.5 86.75 180)
    (property "Author" "Antmicro")
    (property "License" "Apache-2.0")
    (property "MPN" "SRP3212A-1R0M")
    (property "Manufacturer" "Bourns")
    (property "MaxCur" "5.5A")
    (property "Sheetfile" "supply.kicad_sch")
    (property "Sheetname" "Supply")
    (property "Size" "3.2x2.5")
    (property "Val" "1u/5.5A")
    (property "ki_description" "4.4x4.1mm")
    (property "ki_keywords" "Fixed Inductors Ind,3.2x2.5x1mm,1uH+/-20%,5.5A,shd AEC-Q200")
    (attr smd)
    (fp_text reference "L1" (at -0.625 1.75) (layer "B.SilkS")
        (effects (font (size 0.7 0.7) (thickness 0.15)) (justify left bottom mirror))
    )
    (fp_text value "L_1u_5.5A_Bourns-SRP3212A" (at 0.05 -3.301) (layer "B.Fab")
        (effects (font (size 0.7 0.7) (thickness 0.15)) (justify left bottom mirror))
    )
    (fp_text user "License: Apache-2.0" (at -2 -7.701) (layer "B.Fab") hide
        (effects (font (size 0.7 0.7) (thickness 0.15)) (justify left bottom mirror))
    )
    (fp_text user "${REFERENCE}" (at -2 -5.301) (layer "B.Fab") hide
        (effects (font (size 0.7 0.7) (thickness 0.15)) (justify left bottom mirror))
    )
    (fp_text user "Author: Antmicro" (at -2 -6.501) (layer "B.Fab") hide
        (effects (font (size 0.7 0.7) (thickness 0.15)) (justify left bottom mirror))
    )
    (fp_line (start -0.401 -1.249) (end 0.4 -1.249)
      (stroke (width 0.15) (type solid)) (layer "B.SilkS"))
    (fp_line (start -0.401 1.25) (end 0.4 1.25)
      (stroke (width 0.15) (type solid)) (layer "B.SilkS"))
    (fp_circle (center -2.3 0) (end -2.25 0)
      (stroke (width 0.15) (type solid)) (fill solid) (layer "B.SilkS"))
    (fp_rect (start -2 1.5) (end 1.99 -1.49)
      (stroke (width 0.05) (type solid)) (fill none) (layer "B.CrtYd"))
    (fp_line (start -1.601 -1.249) (end -1.601 1.25)
      (stroke (width 0.15) (type solid)) (layer "B.Fab"))
    (fp_line (start -1.601 -1.249) (end 1.6 -1.249)
      (stroke (width 0.15) (type solid)) (layer "B.Fab"))
    (fp_line (start 1.6 1.25) (end -1.601 1.25)
      (stroke (width 0.15) (type solid)) (layer "B.Fab"))
    (fp_line (start 1.6 1.25) (end 1.6 -1.249)
      (stroke (width 0.15) (type solid)) (layer "B.Fab"))
    (pad "1" smd roundrect (at -1.176 0 180) (size 1.35 2.8) (layers "B.Cu" "B.Paste" "B.Mask") (roundrect_rratio 0.25)
      (net 19 "Net-(U2-SW)") (pinfunction "1") (pintype "passive"))
    (pad "2" smd roundrect (at 1.175 0 180) (size 1.35 2.8) (layers "B.Cu" "B.Paste" "B.Mask") (roundrect_rratio 0.25)
      (net 170 "3V3_SSD") (pinfunction "2") (pintype "passive"))
  )
	(footprint "scalenode-cm4-baseboard-footprints:C_1210_3225Metric" (layer "B.Cu")
    (at 106.306 63.712 -90)
    (descr "Capacitor SMD 1210")
    (tags "capacitor SMD 1210")
    (property "Author" "Antmicro")
    (property "Dielectric" "")
    (property "License" "Apache-2.0")
    (property "MPN" "C1210C102KGRACTU")
    (property "Manufacturer" "KEMET")
    (property "Sheetfile" "poe.kicad_sch")
    (property "Sheetname" "PoE")
    (property "Val" "1n")
    (property "Voltage" "2kV")
    (property "ki_description" " ")
    (attr smd)
    (fp_text reference "C50" (at -2.237 -0.919 180) (layer "B.SilkS")
        (effects (font (size 0.7 0.7) (thickness 0.15)) (justify left bottom mirror))
    )
    (fp_text value "C_1n_1210_2kV" (at 0 -2.749 90) (layer "B.Fab")
        (effects (font (size 0.7 0.7) (thickness 0.15)) (justify left bottom mirror))
    )
    (fp_text user "License: Apache-2.0" (at -2.1 -6.749 90) (layer "B.Fab") hide
        (effects (font (size 0.7 0.7) (thickness 0.15)) (justify left bottom mirror))
    )
    (fp_text user "${REFERENCE}" (at -2.1 -4.749 90) (layer "B.Fab") hide
        (effects (font (size 0.7 0.7) (thickness 0.15)) (justify left bottom mirror))
    )
    (fp_text user "Author: Antmicro" (at -2.1 -5.749 90) (layer "B.Fab") hide
        (effects (font (size 0.7 0.7) (thickness 0.15)) (justify left bottom mirror))
    )
    (fp_line (start -0.3 -1.39) (end 0.3 -1.39)
      (stroke (width 0.15) (type solid)) (layer "B.SilkS"))
    (fp_line (start -0.3 1.39) (end 0.3 1.39)
      (stroke (width 0.15) (type solid)) (layer "B.SilkS"))
    (fp_rect (start -2.1 1.75) (end 2.1 -1.75)
      (stroke (width 0.05) (type solid)) (fill none) (layer "B.CrtYd"))
    (fp_rect (start -1.6 1.25) (end 1.6 -1.25)
      (stroke (width 0.15) (type solid)) (fill none) (layer "B.Fab"))
    (pad "1" smd rect (at -1.145 0 270) (size 1.52 3.05) (layers "B.Cu" "B.Paste" "B.Mask")
      (net 11 "GND") (pintype "passive"))
    (pad "2" smd rect (at 1.145 0 270) (size 1.52 3.05) (layers "B.Cu" "B.Paste" "B.Mask")
      (net 230 "Earth") (pintype "passive"))
  )
)
